(kicad_pcb
	(version 20240108)
	(generator "pcbnew")
	(generator_version "8.0")
	(general
		(thickness 1.6)
		(legacy_teardrops no)
	)
	(paper "A4")
	(title_block
		(title "Jetson Orin Baseboard OCuLink Expansion")
		(date "2025-03-18")
		(rev "1.1.0")
		(company "Antmicro Ltd")
		(comment 1 "www.antmicro.com")
		(comment 9 "footprints 60-61 of 119")
	)
	(layers
		(0 "F.Cu" signal)
		(1 "In1.Cu" signal)
		(2 "In2.Cu" signal)
		(31 "B.Cu" signal)
		(32 "B.Adhes" user "B.Adhesive")
		(33 "F.Adhes" user "F.Adhesive")
		(34 "B.Paste" user)
		(35 "F.Paste" user)
		(36 "B.SilkS" user "B.Silkscreen")
		(37 "F.SilkS" user "F.Silkscreen")
		(38 "B.Mask" user)
		(39 "F.Mask" user)
		(40 "Dwgs.User" user "User.Drawings")
		(41 "Cmts.User" user "User.Comments")
		(42 "Eco1.User" user "User.Eco1")
		(43 "Eco2.User" user "User.Eco2")
		(44 "Edge.Cuts" user)
		(45 "Margin" user)
		(46 "B.CrtYd" user "B.Courtyard")
		(47 "F.CrtYd" user "F.Courtyard")
		(48 "B.Fab" user)
		(49 "F.Fab" user)
	)
	(footprint "antmicro-footprints:C_0402_1005Metric"
		(layer "B.Cu")
		(at 122.005 116.687251 -90)
		(descr "Capacitor SMD 0402")
		(tags "capacitor SMD 0402")
		(property "Reference" "C28"
			(at 1.782749 -0.445 90)
			(layer "B.SilkS")
			(effects
				(font
					(size 0.7 0.7)
					(thickness 0.15)
				)
				(justify left bottom mirror)
			)
		)
		(property "Value" "C_100n_0402"
			(at -1.022927 -2.155213 90)
			(layer "B.Fab")
			(effects
				(font
					(size 0.7 0.7)
					(thickness 0.15)
				)
				(justify left bottom mirror)
			)
		)
		(property "Footprint" "antmicro-footprints:C_0402_1005Metric"
			(at 0 0 90)
			(layer "B.Fab")
			(hide yes)
			(effects
				(font
					(size 1.27 1.27)
					(thickness 0.15)
				)
				(justify mirror)
			)
		)
		(property "Datasheet" "https://www.murata.com/products/productdetail?partno=GRM155R61H104KE14%23"
			(at 0 0 90)
			(layer "B.Fab")
			(hide yes)
			(effects
				(font
					(size 1.27 1.27)
					(thickness 0.15)
				)
				(justify mirror)
			)
		)
		(property "Description" "SMD Multilayer Ceramic Capacitor, 0.1 µF, 50 V, 0402 [1005 Metric], ± 10%, X5R, GRM Series"
			(at 0 0 90)
			(layer "B.Fab")
			(hide yes)
			(effects
				(font
					(size 1.27 1.27)
					(thickness 0.15)
				)
				(justify mirror)
			)
		)
		(property "MPN" "GRM155R61H104KE14D"
			(at 0 0 90)
			(unlocked yes)
			(layer "B.Fab")
			(hide yes)
			(effects
				(font
					(size 1 1)
					(thickness 0.15)
				)
				(justify mirror)
			)
		)
		(property "Manufacturer" "Murata"
			(at 0 0 90)
			(unlocked yes)
			(layer "B.Fab")
			(hide yes)
			(effects
				(font
					(size 1 1)
					(thickness 0.15)
				)
				(justify mirror)
			)
		)
		(property "License" "Apache-2.0"
			(at 0 0 90)
			(unlocked yes)
			(layer "B.Fab")
			(hide yes)
			(effects
				(font
					(size 1 1)
					(thickness 0.15)
				)
				(justify mirror)
			)
		)
		(property "Author" "Antmicro"
			(at 0 0 90)
			(unlocked yes)
			(layer "B.Fab")
			(hide yes)
			(effects
				(font
					(size 1 1)
					(thickness 0.15)
				)
				(justify mirror)
			)
		)
		(property "Val" "100n"
			(at 0 0 90)
			(unlocked yes)
			(layer "B.Fab")
			(hide yes)
			(effects
				(font
					(size 1 1)
					(thickness 0.15)
				)
				(justify mirror)
			)
		)
		(property "Voltage" "50V"
			(at 0 0 90)
			(unlocked yes)
			(layer "B.Fab")
			(hide yes)
			(effects
				(font
					(size 1 1)
					(thickness 0.15)
				)
				(justify mirror)
			)
		)
		(property "Dielectric" "X5R"
			(at 0 0 90)
			(unlocked yes)
			(layer "B.Fab")
			(hide yes)
			(effects
				(font
					(size 1 1)
					(thickness 0.15)
				)
				(justify mirror)
			)
		)
		(property "Public" "False"
			(at 0 0 90)
			(unlocked yes)
			(layer "B.Fab")
			(hide yes)
			(effects
				(font
					(size 1 1)
					(thickness 0.15)
				)
				(justify mirror)
			)
		)
		(sheetname "Root")
		(sheetfile "jetson-orin-baseboard-oculink-expansion.kicad_sch")
		(attr smd)
		(fp_rect
			(start -0.925 0.47)
			(end 0.925 -0.47)
			(stroke
				(width 0.05)
				(type default)
			)
			(fill none)
			(layer "B.CrtYd")
		)
		(fp_line
			(start -0.494 0.25)
			(end -0.494 -0.248)
			(stroke
				(width 0.15)
				(type solid)
			)
			(layer "B.Fab")
		)
		(fp_line
			(start 0.504 0.25)
			(end -0.494 0.25)
			(stroke
				(width 0.15)
				(type solid)
			)
			(layer "B.Fab")
		)
		(fp_line
			(start -0.494 -0.248)
			(end 0.504 -0.248)
			(stroke
				(width 0.15)
				(type solid)
			)
			(layer "B.Fab")
		)
		(fp_line
			(start 0.504 -0.248)
			(end 0.504 0.25)
			(stroke
				(width 0.15)
				(type solid)
			)
			(layer "B.Fab")
		)
		(fp_text user "${REFERENCE}"
			(at -0.939 -4.599 90)
			(layer "B.Fab")
			(hide yes)
			(effects
				(font
					(size 0.7 0.7)
					(thickness 0.15)
				)
				(justify left bottom mirror)
			)
		)
		(fp_text user "License: Apache-2.0"
			(at -0.939 -5.799 90)
			(layer "B.Fab")
			(hide yes)
			(effects
				(font
					(size 0.7 0.7)
					(thickness 0.15)
				)
				(justify left bottom mirror)
			)
		)
		(fp_text user "Author: Antmicro"
			(at -0.939 -3.399 90)
			(layer "B.Fab")
			(hide yes)
			(effects
				(font
					(size 0.7 0.7)
					(thickness 0.15)
				)
				(justify left bottom mirror)
			)
		)
		(pad "1" smd roundrect
			(at -0.48 0 270)
			(size 0.59 0.64)
			(layers "B.Cu" "B.Paste" "B.Mask")
			(roundrect_rratio 0.25)
			(net 51 "GND")
			(pintype "passive")
		)
		(pad "2" smd roundrect
			(at 0.48 0 270)
			(size 0.59 0.64)
			(layers "B.Cu" "B.Paste" "B.Mask")
			(roundrect_rratio 0.25)
			(net 23 "+3V3")
			(pintype "passive")
		)
	)
	(footprint "antmicro-footprints:R_0402_1005Metric"
		(layer "B.Cu")
		(at 127.945 130.88775)
		(descr "Resistor SMD 0402")
		(tags "resistor SMD 0402")
		(property "Reference" "R25"
			(at -3.275 -0.37775 0)
			(layer "B.SilkS")
			(effects
				(font
					(size 0.7 0.7)
					(thickness 0.15)
				)
				(justify right top mirror)
			)
		)
		(property "Value" "R_1k_0402"
			(at -1.011843 -1.772047 0)
			(layer "B.Fab")
			(effects
				(font
					(size 0.7 0.7)
					(thickness 0.15)
				)
				(justify right top mirror)
			)
		)
		(property "Footprint" "antmicro-footprints:R_0402_1005Metric"
			(at 0 0 0)
			(layer "B.Fab")
			(hide yes)
			(effects
				(font
					(size 1.27 1.27)
					(thickness 0.15)
				)
				(justify mirror)
			)
		)
		(property "Datasheet" "https://www.bourns.com/docs/product-datasheets/cr.pdf"
			(at 0 0 0)
			(layer "B.Fab")
			(hide yes)
			(effects
				(font
					(size 1.27 1.27)
					(thickness 0.15)
				)
				(justify mirror)
			)
		)
		(property "Description" "SMD Chip Resistor, 1 kohm, ± 1%, 63 mW, 0402 [1005 Metric], Thick Film, General Purpose"
			(at 0 0 0)
			(layer "B.Fab")
			(hide yes)
			(effects
				(font
					(size 1.27 1.27)
					(thickness 0.15)
				)
				(justify mirror)
			)
		)
		(property "MPN" "CR0402-FX-1001GLF"
			(at 0 0 180)
			(unlocked yes)
			(layer "B.Fab")
			(hide yes)
			(effects
				(font
					(size 1 1)
					(thickness 0.15)
				)
				(justify mirror)
			)
		)
		(property "Manufacturer" "Bourns"
			(at 0 0 180)
			(unlocked yes)
			(layer "B.Fab")
			(hide yes)
			(effects
				(font
					(size 1 1)
					(thickness 0.15)
				)
				(justify mirror)
			)
		)
		(property "License" "Apache-2.0"
			(at 0 0 180)
			(unlocked yes)
			(layer "B.Fab")
			(hide yes)
			(effects
				(font
					(size 1 1)
					(thickness 0.15)
				)
				(justify mirror)
			)
		)
		(property "Author" "Antmicro"
			(at 0 0 180)
			(unlocked yes)
			(layer "B.Fab")
			(hide yes)
			(effects
				(font
					(size 1 1)
					(thickness 0.15)
				)
				(justify mirror)
			)
		)
		(property "Val" "1k"
			(at 0 0 180)
			(unlocked yes)
			(layer "B.Fab")
			(hide yes)
			(effects
				(font
					(size 1 1)
					(thickness 0.15)
				)
				(justify mirror)
			)
		)
		(property "Tolerance" "1%"
			(at 0 0 180)
			(unlocked yes)
			(layer "B.Fab")
			(hide yes)
			(effects
				(font
					(size 1 1)
					(thickness 0.15)
				)
				(justify mirror)
			)
		)
		(property "Public" "False"
			(at 0 0 180)
			(unlocked yes)
			(layer "B.Fab")
			(hide yes)
			(effects
				(font
					(size 1 1)
					(thickness 0.15)
				)
				(justify mirror)
			)
		)
		(sheetname "Root")
		(sheetfile "jetson-orin-baseboard-oculink-expansion.kicad_sch")
		(attr smd dnp)
		(fp_rect
			(start -0.925 0.47)
			(end 0.925 -0.47)
			(stroke
				(width 0.05)
				(type default)
			)
			(fill none)
			(layer "B.CrtYd")
		)
		(fp_rect
			(start -0.5 0.25)
			(end 0.5 -0.25)
			(stroke
				(width 0.15)
				(type solid)
			)
			(fill none)
			(layer "B.Fab")
		)
		(fp_text user "Author: Antmicro"
			(at -0.95 -4.169 0)
			(layer "B.Fab")
			(hide yes)
			(effects
				(font
					(size 0.7 0.7)
					(thickness 0.15)
				)
				(justify right top mirror)
			)
		)
		(fp_text user "License: Apache-2.0"
			(at -0.95 -5.169 0)
			(layer "B.Fab")
			(hide yes)
			(effects
				(font
					(size 0.7 0.7)
					(thickness 0.15)
				)
				(justify right top mirror)
			)
		)
		(fp_text user "${REFERENCE}"
			(at -0.95 -3.168 0)
			(layer "B.Fab")
			(hide yes)
			(effects
				(font
					(size 0.7 0.7)
					(thickness 0.15)
				)
				(justify right top mirror)
			)
		)
		(pad "1" smd roundrect
			(at -0.48 0)
			(size 0.59 0.64)
			(layers "B.Cu" "B.Paste" "B.Mask")
			(roundrect_rratio 0.25)
			(net 23 "+3V3")
			(pintype "passive")
		)
		(pad "2" smd roundrect
			(at 0.48 0)
			(size 0.59 0.64)
			(layers "B.Cu" "B.Paste" "B.Mask")
			(roundrect_rratio 0.25)
			(net 100 "/TX_FG0")
			(pintype "passive")
		)
	)
)
